# Stackup_grand teton_MB_18L_2p413mm_EM-890K_VL411_Rev0p6_20230202.xls — Special processing (pcb-stackup)
| Special processing : |  |
| Golden Finger(金手指) | No |
| VIPPO(Via in Pad樹脂填孔) | Yes |
| Back Drill(背鑽) with epoxy plug/fill | Yes |
| Back Drill(背鑽) without epoxy plug/fill | No |
| Laser Drill(雷射鑽孔) | No |
| Low profile oxide(低棕化) | Yes |
| Multi-lamination(多次壓合) | No |
